(kicad_pcb
	(version 20260206)
	(generator "pcbnew")
	(generator_version "10.0")
	(general
		(thickness 1.6)
		(legacy_teardrops no)
	)
	(paper "A4")
	(title_block
		(title "12092022_DA0F0TMDCD0_F0T_Management_Board_D_brd_V3_OCP.brd")
		(comment 1 "Grand Teton / footprints 927-932 of 1440")
	)
	(layers
		(0 "F.Cu" signal "TOP")
		(4 "In1.Cu" signal "GND")
		(6 "In2.Cu" signal "IN1")
		(8 "In3.Cu" signal "GND1")
		(10 "In4.Cu" signal "IN2")
		(12 "In5.Cu" signal "VCC")
		(14 "In6.Cu" signal "VCC1")
		(16 "In7.Cu" signal "IN3")
		(18 "In8.Cu" signal "GND2")
		(20 "In9.Cu" signal "IN4")
		(22 "In10.Cu" signal "GND3")
		(2 "B.Cu" signal "BOTTOM")
		(9 "F.Adhes" user "F.Adhesive")
		(11 "B.Adhes" user "B.Adhesive")
		(13 "F.Paste" user "Package Geometry/Pastemask Top")
		(15 "B.Paste" user "Package Geometry/Pastemask Bottom")
		(5 "F.SilkS" user "Ref Des/Silkscreen Top")
		(7 "B.SilkS" user "Ref Des/Silkscreen Bottom")
		(1 "F.Mask" user "Board Geometry/Soldermask Top")
		(3 "B.Mask" user "Board Geometry/Soldermask Bottom")
		(17 "Dwgs.User" user "User.Drawings")
		(19 "Cmts.User" user "User.Comments")
		(21 "Eco1.User" user "User.Eco1")
		(23 "Eco2.User" user "User.Eco2")
		(25 "Edge.Cuts" user "Board Geometry/Outline")
		(27 "Margin" user)
		(31 "F.CrtYd" user "Package Geometry/Place Bound Top")
		(29 "B.CrtYd" user "Package Geometry/Place Bound Bottom")
		(35 "F.Fab" user "Ref Des/Assembly Top")
		(33 "B.Fab" user "Ref Des/Assembly Bottom")
	)
	(footprint ""
		(layer "B.Cu")
		(at 61.7855 -100.1395 90)
		(property "Reference" "R736"
			(at 0 0 90)
			(layer "B.SilkS")
			(hide yes)
			(effects
				(font
					(size 1.27 1.27)
				)
				(justify mirror)
			)
		)
		(property "Value" ""
			(at 0 0 90)
			(layer "B.Fab")
			(effects
				(font
					(size 1.27 1.27)
				)
				(justify mirror)
			)
		)
		(duplicate_pad_numbers_are_jumpers no)
		(fp_line
			(start 0.7874 -0.4064)
			(end -0.7874 -0.4064)
			(stroke
				(width 0.1524)
				(type default)
			)
			(layer "B.SilkS")
		)
		(fp_line
			(start -0.7874 -0.4064)
			(end -0.7874 0.4064)
			(stroke
				(width 0.1524)
				(type default)
			)
			(layer "B.SilkS")
		)
		(fp_line
			(start 0.7874 0.4064)
			(end 0.7874 -0.4064)
			(stroke
				(width 0.1524)
				(type default)
			)
			(layer "B.SilkS")
		)
		(fp_line
			(start -0.7874 0.4064)
			(end 0.7874 0.4064)
			(stroke
				(width 0.1524)
				(type default)
			)
			(layer "B.SilkS")
		)
		(fp_line
			(start 0.67945 -0.305054)
			(end 0.12065 -0.305054)
			(stroke
				(width 0.1)
				(type default)
			)
			(layer "B.Fab")
		)
		(fp_line
			(start 0.12065 -0.305054)
			(end 0.12065 -0.2794)
			(stroke
				(width 0.1)
				(type default)
			)
			(layer "B.Fab")
		)
		(fp_line
			(start -0.12065 -0.3048)
			(end -0.67945 -0.3048)
			(stroke
				(width 0.1)
				(type default)
			)
			(layer "B.Fab")
		)
		(fp_line
			(start -0.67945 -0.3048)
			(end -0.67945 0.3048)
			(stroke
				(width 0.1)
				(type default)
			)
			(layer "B.Fab")
		)
		(fp_line
			(start 0.12065 -0.2794)
			(end -0.12065 -0.2794)
			(stroke
				(width 0.1)
				(type default)
			)
			(layer "B.Fab")
		)
		(fp_line
			(start -0.12065 -0.2794)
			(end -0.12065 -0.3048)
			(stroke
				(width 0.1)
				(type default)
			)
			(layer "B.Fab")
		)
		(fp_line
			(start 0.12065 0.2794)
			(end 0.12065 0.3048)
			(stroke
				(width 0.1)
				(type default)
			)
			(layer "B.Fab")
		)
		(fp_line
			(start -0.120396 0.2794)
			(end 0.12065 0.2794)
			(stroke
				(width 0.1)
				(type default)
			)
			(layer "B.Fab")
		)
		(fp_line
			(start 0.67945 0.3048)
			(end 0.67945 -0.305054)
			(stroke
				(width 0.1)
				(type default)
			)
			(layer "B.Fab")
		)
		(fp_line
			(start 0.12065 0.3048)
			(end 0.67945 0.3048)
			(stroke
				(width 0.1)
				(type default)
			)
			(layer "B.Fab")
		)
		(fp_line
			(start -0.120396 0.3048)
			(end -0.120396 0.2794)
			(stroke
				(width 0.1)
				(type default)
			)
			(layer "B.Fab")
		)
		(fp_line
			(start -0.67945 0.3048)
			(end -0.120396 0.3048)
			(stroke
				(width 0.1)
				(type default)
			)
			(layer "B.Fab")
		)
		(pad "1" smd circle
			(at 0.40005 0 270)
			(size 0 0)
			(layers "B.Cu" "B.Mask" "B.Paste")
			(net "P3V3_AUX")
		)
		(pad "2" smd circle
			(at -0.40005 0 270)
			(size 0 0)
			(layers "B.Cu" "B.Mask" "B.Paste")
			(net "FM_SOL_UART_CH_SEL_R3")
		)
	)
	(footprint ""
		(layer "B.Cu")
		(at 39.868602 -63.756794 -90)
		(property "Reference" "R196"
			(at 0 0 90)
			(layer "B.SilkS")
			(hide yes)
			(effects
				(font
					(size 1.27 1.27)
				)
				(justify mirror)
			)
		)
		(property "Value" ""
			(at 0 0 90)
			(layer "B.Fab")
			(effects
				(font
					(size 1.27 1.27)
				)
				(justify mirror)
			)
		)
		(duplicate_pad_numbers_are_jumpers no)
		(fp_line
			(start -0.7874 0.4064)
			(end 0.7874 0.4064)
			(stroke
				(width 0.1524)
				(type default)
			)
			(layer "B.SilkS")
		)
		(fp_line
			(start 0.7874 0.4064)
			(end 0.7874 -0.4064)
			(stroke
				(width 0.1524)
				(type default)
			)
			(layer "B.SilkS")
		)
		(fp_line
			(start -0.7874 -0.4064)
			(end -0.7874 0.4064)
			(stroke
				(width 0.1524)
				(type default)
			)
			(layer "B.SilkS")
		)
		(fp_line
			(start 0.7874 -0.4064)
			(end -0.7874 -0.4064)
			(stroke
				(width 0.1524)
				(type default)
			)
			(layer "B.SilkS")
		)
		(fp_line
			(start -0.67945 0.3048)
			(end -0.120396 0.3048)
			(stroke
				(width 0.1)
				(type default)
			)
			(layer "B.Fab")
		)
		(fp_line
			(start -0.120396 0.3048)
			(end -0.120396 0.2794)
			(stroke
				(width 0.1)
				(type default)
			)
			(layer "B.Fab")
		)
		(fp_line
			(start 0.12065 0.3048)
			(end 0.67945 0.3048)
			(stroke
				(width 0.1)
				(type default)
			)
			(layer "B.Fab")
		)
		(fp_line
			(start 0.67945 0.3048)
			(end 0.67945 -0.305054)
			(stroke
				(width 0.1)
				(type default)
			)
			(layer "B.Fab")
		)
		(fp_line
			(start -0.120396 0.2794)
			(end 0.12065 0.2794)
			(stroke
				(width 0.1)
				(type default)
			)
			(layer "B.Fab")
		)
		(fp_line
			(start 0.12065 0.2794)
			(end 0.12065 0.3048)
			(stroke
				(width 0.1)
				(type default)
			)
			(layer "B.Fab")
		)
		(fp_line
			(start -0.12065 -0.2794)
			(end -0.12065 -0.3048)
			(stroke
				(width 0.1)
				(type default)
			)
			(layer "B.Fab")
		)
		(fp_line
			(start 0.12065 -0.2794)
			(end -0.12065 -0.2794)
			(stroke
				(width 0.1)
				(type default)
			)
			(layer "B.Fab")
		)
		(fp_line
			(start -0.67945 -0.3048)
			(end -0.67945 0.3048)
			(stroke
				(width 0.1)
				(type default)
			)
			(layer "B.Fab")
		)
		(fp_line
			(start -0.12065 -0.3048)
			(end -0.67945 -0.3048)
			(stroke
				(width 0.1)
				(type default)
			)
			(layer "B.Fab")
		)
		(fp_line
			(start 0.12065 -0.305054)
			(end 0.12065 -0.2794)
			(stroke
				(width 0.1)
				(type default)
			)
			(layer "B.Fab")
		)
		(fp_line
			(start 0.67945 -0.305054)
			(end 0.12065 -0.305054)
			(stroke
				(width 0.1)
				(type default)
			)
			(layer "B.Fab")
		)
		(pad "1" smd circle
			(at 0.40005 0 90)
			(size 0 0)
			(layers "B.Cu" "B.Mask" "B.Paste")
			(net "P1V2_P1V0_I3C_VDDL1")
		)
		(pad "2" smd circle
			(at -0.40005 0 90)
			(size 0 0)
			(layers "B.Cu" "B.Mask" "B.Paste")
			(net "I3C4_SPD_SCL")
		)
	)
	(footprint ""
		(layer "B.Cu")
		(at 74.095356 -100.93071 180)
		(property "Reference" "C267"
			(at 0 0 0)
			(layer "B.SilkS")
			(hide yes)
			(effects
				(font
					(size 1.27 1.27)
				)
				(justify mirror)
			)
		)
		(property "Value" ""
			(at 0 0 0)
			(layer "B.Fab")
			(effects
				(font
					(size 1.27 1.27)
				)
				(justify mirror)
			)
		)
		(duplicate_pad_numbers_are_jumpers no)
		(fp_line
			(start 0.7874 0.4064)
			(end 0.7874 -0.4064)
			(stroke
				(width 0.1524)
				(type default)
			)
			(layer "B.SilkS")
		)
		(fp_line
			(start 0.7874 -0.4064)
			(end -0.7874 -0.4064)
			(stroke
				(width 0.1524)
				(type default)
			)
			(layer "B.SilkS")
		)
		(fp_line
			(start -0.7874 0.4064)
			(end 0.7874 0.4064)
			(stroke
				(width 0.1524)
				(type default)
			)
			(layer "B.SilkS")
		)
		(fp_line
			(start -0.7874 -0.4064)
			(end -0.7874 0.4064)
			(stroke
				(width 0.1524)
				(type default)
			)
			(layer "B.SilkS")
		)
		(fp_line
			(start 0.67945 0.3048)
			(end 0.67945 -0.305054)
			(stroke
				(width 0.1)
				(type default)
			)
			(layer "B.Fab")
		)
		(fp_line
			(start 0.67945 -0.305054)
			(end 0.12065 -0.305054)
			(stroke
				(width 0.1)
				(type default)
			)
			(layer "B.Fab")
		)
		(fp_line
			(start 0.12065 0.3048)
			(end 0.67945 0.3048)
			(stroke
				(width 0.1)
				(type default)
			)
			(layer "B.Fab")
		)
		(fp_line
			(start 0.12065 0.2794)
			(end 0.12065 0.3048)
			(stroke
				(width 0.1)
				(type default)
			)
			(layer "B.Fab")
		)
		(fp_line
			(start 0.12065 -0.2794)
			(end -0.12065 -0.2794)
			(stroke
				(width 0.1)
				(type default)
			)
			(layer "B.Fab")
		)
		(fp_line
			(start 0.12065 -0.305054)
			(end 0.12065 -0.2794)
			(stroke
				(width 0.1)
				(type default)
			)
			(layer "B.Fab")
		)
		(fp_line
			(start -0.120396 0.3048)
			(end -0.120396 0.2794)
			(stroke
				(width 0.1)
				(type default)
			)
			(layer "B.Fab")
		)
		(fp_line
			(start -0.120396 0.2794)
			(end 0.12065 0.2794)
			(stroke
				(width 0.1)
				(type default)
			)
			(layer "B.Fab")
		)
		(fp_line
			(start -0.12065 -0.2794)
			(end -0.12065 -0.3048)
			(stroke
				(width 0.1)
				(type default)
			)
			(layer "B.Fab")
		)
		(fp_line
			(start -0.12065 -0.3048)
			(end -0.67945 -0.3048)
			(stroke
				(width 0.1)
				(type default)
			)
			(layer "B.Fab")
		)
		(fp_line
			(start -0.67945 0.3048)
			(end -0.120396 0.3048)
			(stroke
				(width 0.1)
				(type default)
			)
			(layer "B.Fab")
		)
		(fp_line
			(start -0.67945 -0.3048)
			(end -0.67945 0.3048)
			(stroke
				(width 0.1)
				(type default)
			)
			(layer "B.Fab")
		)
		(pad "1" smd circle
			(at 0.40005 0)
			(size 0 0)
			(layers "B.Cu" "B.Mask" "B.Paste")
			(net "LPC_ESPI_SEL_R1")
		)
		(pad "2" smd circle
			(at -0.40005 0)
			(size 0 0)
			(layers "B.Cu" "B.Mask" "B.Paste")
			(net "GND")
		)
	)
	(footprint ""
		(layer "B.Cu")
		(at 75.753468 -27.159966)
		(property "Reference" "U19"
			(at 3.304032 2.307336 0)
			(unlocked yes)
			(layer "B.SilkS")
			(effects
				(font
					(size 0.7874 0.5842)
					(thickness 0.1524)
				)
				(justify left mirror)
			)
		)
		(property "Value" ""
			(at 0 0 0)
			(layer "B.Fab")
			(effects
				(font
					(size 1.27 1.27)
				)
				(justify mirror)
			)
		)
		(duplicate_pad_numbers_are_jumpers no)
		(fp_line
			(start -1.954022 -1.549908)
			(end -1.954022 1.549908)
			(stroke
				(width 0.1524)
				(type default)
			)
			(layer "B.SilkS")
		)
		(fp_line
			(start -1.954022 1.549908)
			(end 1.954022 1.549908)
			(stroke
				(width 0.1524)
				(type default)
			)
			(layer "B.SilkS")
		)
		(fp_line
			(start -0.651256 -1.549908)
			(end -1.954022 -1.549908)
			(stroke
				(width 0.1524)
				(type default)
			)
			(layer "B.SilkS")
		)
		(fp_line
			(start 0 -0.898652)
			(end -0.651256 -1.549908)
			(stroke
				(width 0.1524)
				(type default)
			)
			(layer "B.SilkS")
		)
		(fp_line
			(start 0.651256 -1.549908)
			(end 0 -0.898652)
			(stroke
				(width 0.1524)
				(type default)
			)
			(layer "B.SilkS")
		)
		(fp_line
			(start 1.954022 -1.549908)
			(end 0.651256 -1.549908)
			(stroke
				(width 0.1524)
				(type default)
			)
			(layer "B.SilkS")
		)
		(fp_line
			(start 1.954022 1.549908)
			(end 1.954022 -1.549908)
			(stroke
				(width 0.1524)
				(type default)
			)
			(layer "B.SilkS")
		)
		(fp_poly
			(pts
				(xy 5.246624 -0.403352) (xy 4.528312 0.31496) (xy 4.168902 -0.762508)
			)
			(stroke
				(width 0)
				(type default)
			)
			(fill yes)
			(layer "B.SilkS")
		)
		(fp_line
			(start -2.249932 -1.549908)
			(end 2.249932 -1.549908)
			(stroke
				(width 0.1)
				(type default)
			)
			(layer "B.Fab")
		)
		(fp_line
			(start -2.249932 1.549908)
			(end -2.249932 -1.549908)
			(stroke
				(width 0.1)
				(type default)
			)
			(layer "B.Fab")
		)
		(fp_line
			(start 2.249932 -1.549908)
			(end 2.249932 1.549908)
			(stroke
				(width 0.1)
				(type default)
			)
			(layer "B.Fab")
		)
		(fp_line
			(start 2.249932 1.549908)
			(end -2.249932 1.549908)
			(stroke
				(width 0.1)
				(type default)
			)
			(layer "B.Fab")
		)
		(fp_poly
			(pts
				(xy 5.256022 -1.483106) (xy 5.256022 -0.467106) (xy 4.240022 -0.975106)
			)
			(stroke
				(width 0)
				(type default)
			)
			(fill yes)
			(layer "B.Fab")
		)
		(pad "1" smd rect
			(at 2.970022 -0.975106 270)
			(size 0.4318 1.778)
			(layers "B.Cu" "B.Mask" "B.Paste")
			(net "FRU_E0")
		)
		(pad "2" smd rect
			(at 2.970022 -0.32512 270)
			(size 0.4318 1.778)
			(layers "B.Cu" "B.Mask" "B.Paste")
			(net "FRU_E1")
		)
		(pad "3" smd rect
			(at 2.970022 0.32512 270)
			(size 0.4318 1.778)
			(layers "B.Cu" "B.Mask" "B.Paste")
			(net "FRU_E2")
		)
		(pad "4" smd rect
			(at 2.970022 0.975106 270)
			(size 0.4318 1.778)
			(layers "B.Cu" "B.Mask" "B.Paste")
			(net "GND")
		)
		(pad "5" smd rect
			(at -2.970022 0.975106 270)
			(size 0.4318 1.778)
			(layers "B.Cu" "B.Mask" "B.Paste")
			(net "SMB_BMC_MM16_R2_SDA")
		)
		(pad "6" smd rect
			(at -2.970022 0.32512 270)
			(size 0.4318 1.778)
			(layers "B.Cu" "B.Mask" "B.Paste")
			(net "SMB_BMC_MM16_R2_SCL")
		)
		(pad "7" smd rect
			(at -2.970022 -0.32512 270)
			(size 0.4318 1.778)
			(layers "B.Cu" "B.Mask" "B.Paste")
			(net "PD_FRU_WC_N")
		)
		(pad "8" smd rect
			(at -2.970022 -0.975106 270)
			(size 0.4318 1.778)
			(layers "B.Cu" "B.Mask" "B.Paste")
			(net "P3V3_AUX")
		)
	)
	(footprint ""
		(layer "B.Cu")
		(at 39.930832 -47.137828 180)
		(property "Reference" "R267"
			(at 0 0 0)
			(layer "B.SilkS")
			(hide yes)
			(effects
				(font
					(size 1.27 1.27)
				)
				(justify mirror)
			)
		)
		(property "Value" ""
			(at 0 0 0)
			(layer "B.Fab")
			(effects
				(font
					(size 1.27 1.27)
				)
				(justify mirror)
			)
		)
		(duplicate_pad_numbers_are_jumpers no)
		(fp_line
			(start 0.7874 0.4064)
			(end 0.7874 -0.4064)
			(stroke
				(width 0.1524)
				(type default)
			)
			(layer "B.SilkS")
		)
		(fp_line
			(start 0.7874 -0.4064)
			(end -0.7874 -0.4064)
			(stroke
				(width 0.1524)
				(type default)
			)
			(layer "B.SilkS")
		)
		(fp_line
			(start -0.7874 0.4064)
			(end 0.7874 0.4064)
			(stroke
				(width 0.1524)
				(type default)
			)
			(layer "B.SilkS")
		)
		(fp_line
			(start -0.7874 -0.4064)
			(end -0.7874 0.4064)
			(stroke
				(width 0.1524)
				(type default)
			)
			(layer "B.SilkS")
		)
		(fp_line
			(start 0.67945 0.3048)
			(end 0.67945 -0.305054)
			(stroke
				(width 0.1)
				(type default)
			)
			(layer "B.Fab")
		)
		(fp_line
			(start 0.67945 -0.305054)
			(end 0.12065 -0.305054)
			(stroke
				(width 0.1)
				(type default)
			)
			(layer "B.Fab")
		)
		(fp_line
			(start 0.12065 0.3048)
			(end 0.67945 0.3048)
			(stroke
				(width 0.1)
				(type default)
			)
			(layer "B.Fab")
		)
		(fp_line
			(start 0.12065 0.2794)
			(end 0.12065 0.3048)
			(stroke
				(width 0.1)
				(type default)
			)
			(layer "B.Fab")
		)
		(fp_line
			(start 0.12065 -0.2794)
			(end -0.12065 -0.2794)
			(stroke
				(width 0.1)
				(type default)
			)
			(layer "B.Fab")
		)
		(fp_line
			(start 0.12065 -0.305054)
			(end 0.12065 -0.2794)
			(stroke
				(width 0.1)
				(type default)
			)
			(layer "B.Fab")
		)
		(fp_line
			(start -0.120396 0.3048)
			(end -0.120396 0.2794)
			(stroke
				(width 0.1)
				(type default)
			)
			(layer "B.Fab")
		)
		(fp_line
			(start -0.120396 0.2794)
			(end 0.12065 0.2794)
			(stroke
				(width 0.1)
				(type default)
			)
			(layer "B.Fab")
		)
		(fp_line
			(start -0.12065 -0.2794)
			(end -0.12065 -0.3048)
			(stroke
				(width 0.1)
				(type default)
			)
			(layer "B.Fab")
		)
		(fp_line
			(start -0.12065 -0.3048)
			(end -0.67945 -0.3048)
			(stroke
				(width 0.1)
				(type default)
			)
			(layer "B.Fab")
		)
		(fp_line
			(start -0.67945 0.3048)
			(end -0.120396 0.3048)
			(stroke
				(width 0.1)
				(type default)
			)
			(layer "B.Fab")
		)
		(fp_line
			(start -0.67945 -0.3048)
			(end -0.67945 0.3048)
			(stroke
				(width 0.1)
				(type default)
			)
			(layer "B.Fab")
		)
		(pad "1" smd circle
			(at 0.40005 0)
			(size 0 0)
			(layers "B.Cu" "B.Mask" "B.Paste")
			(net "P3V3_AUX")
		)
		(pad "2" smd circle
			(at -0.40005 0)
			(size 0 0)
			(layers "B.Cu" "B.Mask" "B.Paste")
			(net "VOL_SEN_ALERT_R")
		)
	)
	(footprint ""
		(layer "B.Cu")
		(at 46.0502 -61.976 90)
		(property "Reference" "C134"
			(at 0 0 90)
			(layer "B.SilkS")
			(hide yes)
			(effects
				(font
					(size 1.27 1.27)
				)
				(justify mirror)
			)
		)
		(property "Value" ""
			(at 0 0 90)
			(layer "B.Fab")
			(effects
				(font
					(size 1.27 1.27)
				)
				(justify mirror)
			)
		)
		(duplicate_pad_numbers_are_jumpers no)
		(fp_line
			(start 0.7874 -0.4064)
			(end -0.7874 -0.4064)
			(stroke
				(width 0.1524)
				(type default)
			)
			(layer "B.SilkS")
		)
		(fp_line
			(start -0.7874 -0.4064)
			(end -0.7874 0.4064)
			(stroke
				(width 0.1524)
				(type default)
			)
			(layer "B.SilkS")
		)
		(fp_line
			(start 0.7874 0.4064)
			(end 0.7874 -0.4064)
			(stroke
				(width 0.1524)
				(type default)
			)
			(layer "B.SilkS")
		)
		(fp_line
			(start -0.7874 0.4064)
			(end 0.7874 0.4064)
			(stroke
				(width 0.1524)
				(type default)
			)
			(layer "B.SilkS")
		)
		(fp_line
			(start 0.67945 -0.305054)
			(end 0.12065 -0.305054)
			(stroke
				(width 0.1)
				(type default)
			)
			(layer "B.Fab")
		)
		(fp_line
			(start 0.12065 -0.305054)
			(end 0.12065 -0.2794)
			(stroke
				(width 0.1)
				(type default)
			)
			(layer "B.Fab")
		)
		(fp_line
			(start -0.12065 -0.3048)
			(end -0.67945 -0.3048)
			(stroke
				(width 0.1)
				(type default)
			)
			(layer "B.Fab")
		)
		(fp_line
			(start -0.67945 -0.3048)
			(end -0.67945 0.3048)
			(stroke
				(width 0.1)
				(type default)
			)
			(layer "B.Fab")
		)
		(fp_line
			(start 0.12065 -0.2794)
			(end -0.12065 -0.2794)
			(stroke
				(width 0.1)
				(type default)
			)
			(layer "B.Fab")
		)
		(fp_line
			(start -0.12065 -0.2794)
			(end -0.12065 -0.3048)
			(stroke
				(width 0.1)
				(type default)
			)
			(layer "B.Fab")
		)
		(fp_line
			(start 0.12065 0.2794)
			(end 0.12065 0.3048)
			(stroke
				(width 0.1)
				(type default)
			)
			(layer "B.Fab")
		)
		(fp_line
			(start -0.120396 0.2794)
			(end 0.12065 0.2794)
			(stroke
				(width 0.1)
				(type default)
			)
			(layer "B.Fab")
		)
		(fp_line
			(start 0.67945 0.3048)
			(end 0.67945 -0.305054)
			(stroke
				(width 0.1)
				(type default)
			)
			(layer "B.Fab")
		)
		(fp_line
			(start 0.12065 0.3048)
			(end 0.67945 0.3048)
			(stroke
				(width 0.1)
				(type default)
			)
			(layer "B.Fab")
		)
		(fp_line
			(start -0.120396 0.3048)
			(end -0.120396 0.2794)
			(stroke
				(width 0.1)
				(type default)
			)
			(layer "B.Fab")
		)
		(fp_line
			(start -0.67945 0.3048)
			(end -0.120396 0.3048)
			(stroke
				(width 0.1)
				(type default)
			)
			(layer "B.Fab")
		)
		(pad "1" smd circle
			(at 0.40005 0 270)
			(size 0 0)
			(layers "B.Cu" "B.Mask" "B.Paste")
			(net "GND")
		)
		(pad "2" smd circle
			(at -0.40005 0 270)
			(size 0 0)
			(layers "B.Cu" "B.Mask" "B.Paste")
			(net "A_BMC_ADCVREFN0")
		)
	)
)
